(
  (version 16.5)
  (tool
    (creator "conceptHDL")
    (last "conceptHDL")
  )
  (library "mstr_symbols")
  (design "p12v_stby"
    (lastIds
      (lastNetId 4)
    )
    (nets
      ("N1" "g" -1 -1 1 3)
      ("N2" "page1_g" -1 -1 0 )
      ("N4" "page1_p12v_stby" -1 -1 0 )
      ("N3" "p12v_stby" -1 -1 2 )
    )

    (alias
      ("N2" -1 -1 "N1" -1 -1)
      ("N4" -1 -1 "N2" -1 -1)
      ("N4" -1 -1 "N3" -1 -1)
    )

  )
)
